%FSTAX23Y23*%
%MOIN*%
%SFA1B1*%

%IPPOS*%
%ADD59R,0.165350X0.125980*%
%ADD79R,0.314960X0.135830*%
%ADD80R,1.354330X0.230320*%
%ADD81O,0.086740X0.031620*%
%ADD82R,0.047370X0.082800*%
%ADD83R,0.078870X0.082800*%
%ADD84R,0.063910X0.069020*%
%ADD85R,0.025720X0.062330*%
%ADD86R,0.072960X0.059180*%
%ADD87R,0.086740X0.106420*%
%ADD88R,0.027690X0.098550*%
%ADD89R,0.049340X0.047370*%
%ADD90R,0.094610X0.049340*%
%ADD91R,0.027690X0.043430*%
%ADD92O,0.065090X0.025720*%
%ADD93R,0.085560X0.030440*%
%ADD94R,0.033590X0.049340*%
%ADD95R,0.059180X0.082800*%
%ADD96R,0.047370X0.078870*%
%ADD97R,0.047370X0.098550*%
%ADD98R,0.049340X0.053280*%
%ADD99R,0.035560X0.053280*%
%ADD100R,0.061150X0.035560*%
%ADD101R,0.058000X0.208000*%
%ADD102R,0.065090X0.045400*%
%ADD103R,0.036350X0.047370*%
%ADD104R,0.033590X0.031620*%
%ADD105R,0.036000X0.173000*%
%ADD106R,0.036000X0.134000*%
%ADD107R,0.039500X0.074930*%
%ADD108R,0.078870X0.017840*%
%ADD109R,0.034580X0.017840*%
%ADD110R,0.017840X0.030640*%
%ADD111R,0.035560X0.043430*%
%ADD112R,0.046580X0.042250*%
%ADD113R,0.220600X0.122170*%
%ADD114R,0.104460X0.132020*%
%ADD115R,0.041470X0.047370*%
%ADD116R,0.065090X0.053280*%
%ADD117R,0.045400X0.047370*%
%ADD118R,0.033200X0.034770*%
%ADD119R,0.018830X0.017840*%
%ADD120R,0.017840X0.018830*%
%ADD121R,0.069020X0.017840*%
%ADD122R,0.074930X0.061150*%
%ADD123R,0.017840X0.069020*%
%ADD124R,0.061150X0.074930*%
%ADD125R,0.053280X0.065090*%
%ADD126R,0.034770X0.033200*%
%ADD127R,0.047370X0.045400*%
%ADD128R,0.047370X0.041470*%
%ADD129R,0.047370X0.036350*%
%ADD130R,0.031620X0.033590*%
%ADD131R,0.090870X0.052090*%
%ADD132R,0.043430X0.035560*%
%ADD133C,0.039500*%
%ADD134C,0.073980*%
%ADD135C,0.008000*%
%ADD136C,0.069020*%
%ADD137R,0.069020X0.069020*%
%ADD138C,0.083000*%
%ADD139C,0.106420*%
%ADD140O,0.096580X0.185170*%
%ADD141O,0.185170X0.096580*%
%ADD142O,0.204850X0.106420*%
%ADD143C,0.120000*%
%ADD144C,0.128000*%
%ADD145R,0.008000X0.008000*%
%ADD146C,0.029660*%
%ADD147C,0.063000*%
%ADD148R,0.063000X0.063000*%
%ADD149C,0.058000*%
%ADD150C,0.250000*%
%ADD151C,0.024000*%
%ADD152C,0.208000*%
%LNgrandmaster-1*%
%LPD*%
G54D59*
X04909Y03961D03*
Y02808D03*
G54D79*
X0147Y00245D03*
G54D80*
X02446Y00111D03*
G54D81*
X02756Y03287D03*
Y03237D03*
Y03187D03*
Y03137D03*
Y03087D03*
Y03037D03*
Y02987D03*
Y02937D03*
X03111Y03287D03*
Y03237D03*
Y03187D03*
Y03137D03*
Y03087D03*
Y03037D03*
Y02987D03*
Y02937D03*
G54D82*
X02271Y04275D03*
G54D83*
X02377Y04275D03*
G54D84*
X02234Y04173D03*
X0243D03*
G54D85*
X02383Y0417D03*
X02358D03*
X02332D03*
X02306D03*
X02281D03*
G54D86*
X02465Y04275D03*
X02199D03*
G54D87*
X04046Y04244D03*
Y04027D03*
X03696D03*
Y04244D03*
G54D88*
X03934Y04023D03*
X03902D03*
X03871D03*
X03839D03*
X03808D03*
G54D89*
X00594Y00906D03*
Y01956D03*
Y02481D03*
Y01431D03*
G54D90*
X00654Y00964D03*
Y00847D03*
Y01897D03*
Y02014D03*
Y02422D03*
Y02539D03*
Y01489D03*
Y01372D03*
G54D91*
X03469Y03661D03*
X03444Y0375D03*
X03495D03*
X02834Y03661D03*
X02809Y0375D03*
X0286D03*
X02719Y03661D03*
X02694Y0375D03*
X02745D03*
X03244Y03661D03*
X03219Y0375D03*
X0327D03*
G54D92*
X01846Y04024D03*
Y04049D03*
Y04074D03*
Y04099D03*
Y04124D03*
Y04149D03*
Y04174D03*
Y04199D03*
X01631Y04024D03*
Y04049D03*
Y04074D03*
Y04099D03*
Y04124D03*
Y04149D03*
Y04174D03*
Y04199D03*
X03987Y03683D03*
Y03708D03*
Y03733D03*
Y03758D03*
Y03783D03*
Y03808D03*
Y03833D03*
Y03858D03*
X03772Y03683D03*
Y03708D03*
Y03733D03*
Y03758D03*
Y03783D03*
Y03808D03*
Y03833D03*
Y03858D03*
G54D93*
X06352Y02241D03*
Y02291D03*
Y02341D03*
Y02391D03*
X06157D03*
Y02341D03*
Y02291D03*
Y02241D03*
X06637Y02031D03*
Y01981D03*
Y01931D03*
Y01881D03*
X06832D03*
Y01931D03*
Y01981D03*
Y02031D03*
G54D94*
X06341Y03701D03*
X06197D03*
X06031D03*
X05887D03*
X06202Y03566D03*
X06346D03*
G54D95*
X06726Y03168D03*
X06943D03*
Y03294D03*
X06726D03*
G54D96*
X03451Y03206D03*
X03392D03*
X03451Y03395D03*
X0351D03*
X03569Y03206D03*
X03333Y03395D03*
Y03206D03*
X0351D03*
X03392Y03395D03*
G54D97*
X03569Y03385D03*
G54D98*
X03438Y03051D03*
Y02892D03*
X03531Y03051D03*
Y02892D03*
G54D99*
X03484Y02892D03*
Y03051D03*
G54D100*
X03444Y02995D03*
Y02948D03*
X03525D03*
Y02995D03*
G54D101*
X03344Y04221D03*
Y03951D03*
X03244Y04221D03*
Y03951D03*
X03144Y04221D03*
Y03951D03*
X03044Y04221D03*
Y03951D03*
X02944Y04221D03*
Y03951D03*
G54D102*
X03349Y03666D03*
Y03745D03*
X02944Y03666D03*
Y03745D03*
X03044Y03666D03*
Y03745D03*
X03144Y03666D03*
Y03745D03*
G54D103*
X03477Y02797D03*
X03532D03*
X06035Y03556D03*
X0609D03*
X0415Y03603D03*
X04204D03*
X06897Y01816D03*
X06842D03*
X06782D03*
X06727D03*
X06367Y02451D03*
X06312D03*
X04167Y03701D03*
X04112D03*
X04652Y04206D03*
X04707D03*
X05212D03*
X05267D03*
X04652Y04121D03*
X04707D03*
X05267Y04126D03*
X05212D03*
G54D104*
X03701Y03786D03*
X03668D03*
X03701Y03861D03*
X03668D03*
G54D105*
X02545Y00137D03*
X02466D03*
X02348D03*
X0282D03*
X01915D03*
X02033D03*
X02663D03*
X02702D03*
X0286D03*
X02978D03*
X0219D03*
X01994D03*
X01954D03*
X03017D03*
X02309D03*
X02112D03*
X02151D03*
X02387D03*
X02427D03*
X02584D03*
X02624D03*
X02742D03*
X02781D03*
X02899D03*
X02938D03*
X02505D03*
X02072D03*
X01797D03*
X01836D03*
X01875D03*
X03096D03*
G54D106*
X03057Y00157D03*
G54D107*
X04957Y04206D03*
X05091D03*
X04432D03*
X04566D03*
G54D108*
X04068Y01599D03*
X03911D03*
Y01619D03*
X04068D03*
X03911Y01639D03*
X04068D03*
X03911Y01659D03*
X04068D03*
X03911Y01679D03*
X04068D03*
X03911Y01699D03*
X04068D03*
X03911Y01719D03*
X04068D03*
X03911Y01739D03*
X04068D03*
X03911Y01759D03*
X04068D03*
X03911Y01779D03*
X04068D03*
G54D109*
X06511Y03191D03*
Y03172D03*
Y03211D03*
Y03231D03*
Y0325D03*
Y0327D03*
Y0329D03*
Y03309D03*
Y03329D03*
X06388D03*
Y03309D03*
Y0329D03*
Y0327D03*
Y0325D03*
Y03231D03*
Y03211D03*
Y03191D03*
Y03172D03*
Y03152D03*
X06511D03*
G54D110*
X06479Y03332D03*
X06459D03*
X0644D03*
X0642D03*
Y0315D03*
X0644D03*
X06459D03*
X06479D03*
G54D111*
X00901Y00718D03*
X0096D03*
X00908Y02284D03*
X00967D03*
X009Y01747D03*
X00959D03*
X00904Y01224D03*
X00963D03*
G54D112*
X04149Y02789D03*
Y02842D03*
X04434Y02789D03*
Y02842D03*
G54D113*
X06679Y0242D03*
Y02802D03*
X06319Y01842D03*
Y0146D03*
G54D114*
X01157Y00906D03*
X00932D03*
Y01956D03*
X01157D03*
X00932Y02481D03*
X01157D03*
Y01431D03*
X00932D03*
G54D115*
X01249Y04254D03*
Y04197D03*
X03589Y03852D03*
Y03909D03*
Y03784D03*
Y03727D03*
X00644Y04197D03*
Y04254D03*
X00846Y04197D03*
Y04254D03*
X01048D03*
Y04197D03*
G54D116*
X04339Y0278D03*
Y02851D03*
X06334Y0211D03*
Y02181D03*
X06659Y02166D03*
Y02095D03*
X06253Y02826D03*
Y02755D03*
X06372Y02826D03*
Y02755D03*
X04104Y0377D03*
Y03841D03*
X02209Y03716D03*
Y03645D03*
X02639Y03535D03*
Y03606D03*
X03693Y03188D03*
Y03117D03*
X04064Y0278D03*
Y02851D03*
X03959Y0278D03*
Y02851D03*
X04234Y0278D03*
Y02851D03*
G54D117*
X04039Y03029D03*
Y03092D03*
X06469Y02239D03*
Y02302D03*
X06519Y01954D03*
Y02017D03*
X04194Y03774D03*
Y03837D03*
X03688Y03266D03*
Y03329D03*
X06604Y03264D03*
Y03327D03*
Y03192D03*
Y03129D03*
G54D118*
X04109Y03044D03*
Y03077D03*
X06939Y01889D03*
Y01922D03*
X06064Y02344D03*
Y02377D03*
X06584Y03039D03*
Y03072D03*
X02139Y03697D03*
Y03664D03*
X02724Y03559D03*
Y03592D03*
X03769Y03234D03*
Y03201D03*
X04454Y03044D03*
Y03077D03*
X04394Y03044D03*
Y03077D03*
X04334Y03044D03*
Y03077D03*
X04274Y03044D03*
Y03077D03*
X04219Y03044D03*
Y03077D03*
X04164Y03044D03*
Y03077D03*
G54D119*
X03269Y02834D03*
Y02814D03*
Y02795D03*
X03209D03*
Y02814D03*
Y02834D03*
G54D120*
X03249Y02784D03*
X03229D03*
Y02845D03*
X03249D03*
G54D121*
X03492Y01398D03*
Y01378D03*
Y01457D03*
Y01477D03*
Y01772D03*
Y01496D03*
Y01792D03*
Y0189D03*
Y01851D03*
Y0187D03*
Y01831D03*
X03651Y0187D03*
Y0189D03*
Y01929D03*
X03492Y01339D03*
Y01359D03*
X03651Y01792D03*
Y01772D03*
Y01851D03*
Y01831D03*
Y01949D03*
Y01988D03*
Y01969D03*
X03492Y01988D03*
Y01969D03*
X03651Y01693D03*
X03492Y01634D03*
Y01673D03*
Y01654D03*
Y01693D03*
X03651Y01733D03*
Y01752D03*
Y01654D03*
Y01575D03*
Y01555D03*
Y01673D03*
Y01634D03*
X03492Y01929D03*
Y01555D03*
Y02008D03*
Y0191D03*
Y01811D03*
Y01713D03*
Y01614D03*
Y01516D03*
Y01418D03*
X03651Y02008D03*
Y0191D03*
Y01811D03*
Y01713D03*
Y01614D03*
Y01516D03*
Y01418D03*
X03492Y01949D03*
X03651Y01595D03*
X03492Y01536D03*
X03651Y01496D03*
Y01477D03*
Y01457D03*
Y01437D03*
Y01398D03*
Y01378D03*
Y01359D03*
Y01339D03*
X03492Y01319D03*
X03651D03*
X03492Y01733D03*
Y01752D03*
X03651Y01536D03*
X03492Y01575D03*
Y01595D03*
Y01437D03*
Y02087D03*
Y02067D03*
Y02047D03*
Y02028D03*
X03651Y02087D03*
Y02067D03*
Y02047D03*
Y02028D03*
X01776Y01634D03*
Y01614D03*
Y0187D03*
Y02028D03*
Y0191D03*
Y01831D03*
Y01949D03*
Y01733D03*
Y01772D03*
X01617Y01929D03*
Y01851D03*
Y0191D03*
Y02028D03*
X01776Y02008D03*
Y01969D03*
Y01457D03*
Y01674D03*
X01617Y0187D03*
Y01969D03*
X01776Y01929D03*
Y01851D03*
Y01811D03*
Y01654D03*
X01617Y02008D03*
X01776Y01752D03*
Y01713D03*
X01617Y01949D03*
X01776Y01555D03*
Y01575D03*
X01617Y01516D03*
Y01457D03*
Y01811D03*
Y01831D03*
X01776Y01437D03*
X01617Y01359D03*
X01776Y01339D03*
X01617Y01575D03*
Y01437D03*
Y01536D03*
Y01555D03*
Y01614D03*
Y01733D03*
Y01674D03*
Y01378D03*
Y01477D03*
Y01418D03*
Y01752D03*
X01776Y01359D03*
X01617Y01339D03*
Y01634D03*
Y01772D03*
X01776Y01378D03*
Y01319D03*
Y01418D03*
X01617Y01319D03*
X01776Y01477D03*
X01617Y01713D03*
Y01654D03*
X01776Y01516D03*
X01617Y02048D03*
X01776D03*
Y01398D03*
Y01496D03*
Y01595D03*
Y01693D03*
Y01792D03*
Y0189D03*
Y01988D03*
X01617Y01398D03*
Y01496D03*
Y01595D03*
Y01693D03*
Y01792D03*
Y0189D03*
Y01988D03*
Y02087D03*
X01776D03*
Y02067D03*
Y01536D03*
X01617Y02067D03*
G54D122*
X03571Y02131D03*
Y01275D03*
X01696Y01275D03*
Y02131D03*
G54D123*
X0298Y02518D03*
Y02358D03*
X02882Y02518D03*
X02783D03*
X02685D03*
X02586D03*
X02488D03*
X0239D03*
X02291D03*
X02882Y02358D03*
X02783D03*
X02685D03*
X02586D03*
X02488D03*
X0239D03*
X02291D03*
X02941D03*
X02961D03*
X02901D03*
X02921D03*
X02842D03*
X02862D03*
X02803D03*
X02823D03*
X02744D03*
X02764D03*
X02705D03*
X02724D03*
X02646D03*
X02665D03*
X02606D03*
X02626D03*
X02547D03*
X02567D03*
X02508D03*
X02527D03*
X02449D03*
X02468D03*
X02409D03*
X02429D03*
X0235D03*
X0237D03*
X02212Y02518D03*
X02232D03*
Y02358D03*
X02212D03*
X02252Y02518D03*
X02272D03*
X02409D03*
X02429D03*
X0235D03*
X0237D03*
X02508D03*
X02527D03*
X02449D03*
X02468D03*
X02606D03*
X02547D03*
X02626D03*
X02567D03*
X02705D03*
X02724D03*
X02646D03*
X02665D03*
X02803D03*
X02823D03*
X02744D03*
X02764D03*
X02901D03*
X02921D03*
X02842D03*
X02862D03*
X02941D03*
X02961D03*
X02252Y02358D03*
X02311D03*
X02331D03*
X02272D03*
X02311Y02518D03*
X02331D03*
X02803Y01038D03*
X02823D03*
X02862Y00878D03*
X02882D03*
X02744D03*
X02764D03*
X02685Y01038D03*
X02705D03*
X02587Y00878D03*
Y01038D03*
X02646Y00878D03*
X02626D03*
X02744Y01038D03*
X02764D03*
X02803Y00878D03*
X02823D03*
X02685D03*
X02705D03*
X02626Y01038D03*
X02646D03*
X02232Y00878D03*
X02429D03*
X0237D03*
X0235D03*
X02331D03*
X02291D03*
X0239D03*
X02488D03*
X02527D03*
X02547D03*
X02567D03*
X02449D03*
X02468D03*
X02252D03*
X02272D03*
X02567Y01038D03*
X0237D03*
X0239D03*
X02429D03*
X02468D03*
X02488D03*
X02449D03*
X02291D03*
X02272D03*
X02252D03*
X02232D03*
X0235D03*
X02331D03*
X02547D03*
X02527D03*
X02862D03*
X02882D03*
X02921Y00878D03*
Y01038D03*
X02941Y00878D03*
Y01038D03*
X0298Y00878D03*
Y01038D03*
X02961D03*
Y00878D03*
X02901Y01038D03*
X02842D03*
X02783D03*
X02724D03*
X02665D03*
X02606D03*
X02508D03*
X02409D03*
X02311D03*
X02901Y00878D03*
X02842D03*
X02783D03*
X02724D03*
X02665D03*
X02606D03*
X02508D03*
X02409D03*
X02311D03*
X02212D03*
Y01038D03*
G54D124*
X02168Y02438D03*
X02168Y00958D03*
X03024D03*
X03024Y02438D03*
G54D125*
X05741Y03361D03*
X05812D03*
X06629Y01421D03*
X067D03*
X06629Y01531D03*
X067D03*
X06439Y03071D03*
X0651D03*
X0373Y00726D03*
X03659D03*
X01802Y04276D03*
X01873D03*
X0428Y03246D03*
X04209D03*
G54D126*
X05634Y03359D03*
X05668D03*
X06327Y02656D03*
X06361D03*
X06327Y02501D03*
X06361D03*
X06327Y02556D03*
X06361D03*
X06327Y02611D03*
X06361D03*
X06676Y01611D03*
X06642D03*
X06676Y01671D03*
X06642D03*
X06676Y01721D03*
X06642D03*
X06676Y01776D03*
X06642D03*
X03716Y00636D03*
X03682D03*
G54D127*
X06906Y02096D03*
X06843D03*
X06093Y02171D03*
X06156D03*
X01664Y04273D03*
X01727D03*
G54D128*
X04275Y03603D03*
X04332D03*
G54D129*
X06749Y02143D03*
Y02088D03*
X06234Y02183D03*
Y02128D03*
X07009Y01883D03*
Y01938D03*
X06004Y02393D03*
Y02338D03*
X02146Y02624D03*
Y02679D03*
X00638Y04038D03*
Y04093D03*
X0084D03*
Y04038D03*
X01042Y04093D03*
Y04038D03*
X01243Y04093D03*
Y04038D03*
X06122Y02488D03*
Y02433D03*
X01933Y04074D03*
Y04129D03*
G54D130*
X02503Y00607D03*
Y00573D03*
X03055Y00607D03*
Y00573D03*
G54D131*
X02334Y03404D03*
Y03483D03*
Y03562D03*
Y0364D03*
X02509Y03404D03*
Y03562D03*
Y03483D03*
Y0364D03*
G54D132*
X01346Y04082D03*
Y04141D03*
Y04037D03*
Y03978D03*
X02151Y04015D03*
Y04074D03*
X02212Y04015D03*
Y04074D03*
X02387Y02899D03*
Y02958D03*
G54D133*
X03958Y04126D03*
X03784D03*
G54D134*
X03294Y04086D03*
X02994D03*
G54D135*
X02422Y03082D03*
Y03239D03*
Y03601D03*
Y03443D03*
G54D136*
X05327Y02307D03*
X05127D03*
X04927D03*
X04727D03*
X04927Y01007D03*
X05127D03*
X04327Y02307D03*
X05327Y01007D03*
G54D137*
X04327Y01007D03*
G54D138*
X05578Y0089D03*
Y01689D03*
Y02489D03*
X03979D03*
Y0089D03*
X04062Y02595D03*
X0418D03*
X04298D03*
G54D139*
X05723Y04025D03*
Y03844D03*
X069Y03806D03*
Y03589D03*
X06734D03*
Y03806D03*
X06569Y03589D03*
Y03806D03*
G54D140*
X05934Y03937D03*
G54D141*
X06119Y04056D03*
G54D142*
X06119Y03819D03*
G54D143*
X00199Y00906D03*
Y02481D03*
Y01956D03*
Y01431D03*
G54D144*
X00299Y01006D03*
Y00806D03*
X00099D03*
Y01006D03*
X00299Y02581D03*
Y02381D03*
X00099D03*
Y02581D03*
X00299Y02056D03*
Y01856D03*
X00099D03*
Y02056D03*
X00299Y01531D03*
Y01331D03*
X00099D03*
Y01531D03*
G54D145*
X03617Y02486D03*
X01652Y00916D03*
X01651Y02486D03*
X03617Y00916D03*
G54D146*
X03571Y02097D03*
Y01309D03*
X02203Y02438D03*
X01696Y01309D03*
Y02097D03*
X02203Y00958D03*
X0299D03*
X0299Y02438D03*
G54D147*
X02043Y04157D03*
Y04057D03*
X01457Y04153D03*
Y04053D03*
G54D148*
X02043Y04257D03*
X01457Y04253D03*
G54D149*
X069Y04093D03*
X06569D03*
G54D150*
X00285Y04152D03*
Y00368D03*
G54D151*
X02494Y02661D03*
X02692Y02721D03*
X02511Y00405D03*
X0261Y00279D03*
X02578D03*
X0298Y00409D03*
X02821Y00407D03*
X02748Y00282D03*
X02469Y0041D03*
X02905Y00279D03*
X02878Y00249D03*
X02692Y00795D03*
X02665D03*
X02854Y00405D03*
X02779Y00279D03*
X02665Y00405D03*
X02704D03*
X0235D03*
X02389D03*
X02937Y00279D03*
X02957Y00251D03*
X03019Y00405D03*
X0274Y00976D03*
X02767D03*
X02732Y00795D03*
X02681Y00976D03*
X02708D03*
X02447Y00242D03*
X02413Y00279D03*
X02444D03*
X02606Y00931D03*
X02625Y00795D03*
X02598D03*
X02636Y00247D03*
X02799Y00251D03*
X02826Y00976D03*
X02799D03*
X02649D03*
X02622D03*
X02759Y00795D03*
X02799D03*
X02826D03*
X02862D03*
X02893D03*
X02409Y01088D03*
X02311Y0109D03*
X02508Y00931D03*
X02409Y00932D03*
X02724Y01093D03*
X02784Y01094D03*
X02842Y01095D03*
X02546Y00244D03*
X03097Y00251D03*
X02475Y02291D03*
X0233Y02215D03*
X01798Y01304D03*
X02606Y01091D03*
X03554Y01841D03*
X03719Y01996D03*
X03894Y01566D03*
X03379Y01386D03*
X01721Y0189D03*
X01671Y01792D03*
X01674Y01989D03*
X02508Y0109D03*
X03413Y01573D03*
X0167Y01595D03*
X01754Y02126D03*
X02409Y02579D03*
X02586Y02569D03*
X03197Y01714D03*
X03439Y0187D03*
X03298Y01971D03*
X02985Y02287D03*
X02702Y02289D03*
X02821Y02601D03*
X01718Y01792D03*
X02881Y02566D03*
X03732Y01418D03*
X03554Y01891D03*
X02253Y02279D03*
X02272Y02463D03*
X01719Y01536D03*
X02311Y00934D03*
X03571Y02033D03*
X03554Y01991D03*
X02942Y02286D03*
X02841Y02263D03*
X02394Y0272D03*
X01567Y01285D03*
X01675Y01891D03*
X01568Y02067D03*
X02783Y02429D03*
X03719Y01921D03*
X03773Y01666D03*
X02599Y02436D03*
X02494Y02696D03*
X02894Y02431D03*
X02665Y01092D03*
X02475Y02456D03*
X03414Y01805D03*
X03404Y01363D03*
X02579Y02281D03*
X02685Y02311D03*
X0359Y01662D03*
X02404Y02412D03*
X02803Y02307D03*
X01716Y01399D03*
X01721Y01989D03*
X01619Y02121D03*
X03549Y01413D03*
X02488Y02413D03*
X02726Y02293D03*
X01822Y01674D03*
X0167Y01694D03*
X01884Y02071D03*
X02901Y01095D03*
X0292Y02428D03*
X01893Y01693D03*
X03594Y01514D03*
X0245Y02282D03*
X02409Y02314D03*
X02958Y02621D03*
X03406Y01461D03*
X0341Y01713D03*
X03252Y01661D03*
X02933Y00953D03*
X02871Y02297D03*
X02685Y02568D03*
X03571Y02058D03*
X03804Y0184D03*
X01879Y01811D03*
X03554Y01941D03*
X03392Y01871D03*
X03407Y01411D03*
X02575Y02412D03*
X02499Y02236D03*
X02409Y02283D03*
X02783Y02568D03*
X02948Y02456D03*
X03549Y01441D03*
X03718Y01713D03*
X02624Y02461D03*
X01897Y01516D03*
X03834Y01481D03*
X03864Y01511D03*
X03924Y01536D03*
X03719Y01766D03*
X03329Y01826D03*
X02645Y02274D03*
X02665Y02291D03*
X01721Y01694D03*
X01671Y01399D03*
X02581Y02308D03*
X03803Y01691D03*
X03224Y01661D03*
X02252Y02613D03*
X01718Y01497D03*
X01714Y01595D03*
X01671Y01497D03*
X02321Y02586D03*
X03379Y01336D03*
X01797Y00355D03*
X02034Y00246D03*
X01916Y00244D03*
X02309Y00246D03*
X0333Y03301D03*
X0412Y03594D03*
X01393Y01816D03*
X0099Y00687D03*
X04794Y02808D03*
X03183Y03135D03*
X03277Y02963D03*
X03197Y0297D03*
X03491Y03103D03*
X03188Y03187D03*
X0323Y03235D03*
X03358Y03448D03*
X03068Y03395D03*
X02419Y02788D03*
X02146Y02753D03*
X03275Y03141D03*
X03056Y01811D03*
X02413Y03295D03*
X02254Y03536D03*
X02579Y03486D03*
X02389Y03481D03*
X02321Y03361D03*
X02434Y03546D03*
X02634Y03406D03*
X02631Y02876D03*
X02591Y03186D03*
X0259Y03288D03*
X00996Y02256D03*
X02004Y01336D03*
X02028Y01361D03*
X02549Y01755D03*
X02418Y03118D03*
X02414Y03199D03*
X02462Y03172D03*
X02473Y0298D03*
X02146Y04103D03*
X02253Y04086D03*
X01408Y0398D03*
X01345Y04175D03*
X00996Y01187D03*
X00988Y01717D03*
X00937Y02317D03*
X02353Y04017D03*
X01726Y04329D03*
X01788D03*
X04477Y03135D03*
X04064Y02722D03*
X06628Y01372D03*
X04039Y02406D03*
X06974Y01939D03*
X04134Y01651D03*
X03994Y01551D03*
X04134Y01751D03*
X04151Y01623D03*
X03968Y01671D03*
X03969Y01552D03*
X03944Y01816D03*
X04131Y01686D03*
X04179Y01601D03*
X04034Y01546D03*
X03996Y01711D03*
X04064Y01796D03*
Y01511D03*
X03263Y03303D03*
X0396Y02724D03*
X01569Y04171D03*
X02076Y00255D03*
Y00287D03*
X02112D03*
X02151D03*
X02112Y00255D03*
X02151D03*
X01832D03*
X01852D03*
X01872D03*
X01832Y00287D03*
X01852D03*
X01872D03*
X06253Y02909D03*
X06647Y03129D03*
X05267Y04088D03*
X04339Y02725D03*
X04503Y02789D03*
X02231Y02584D03*
X05994Y03552D03*
X04049Y03665D03*
X03829Y03806D03*
X05577Y02214D03*
X02694Y01481D03*
X02384Y01941D03*
X0383Y03762D03*
X06334Y03266D03*
X03744Y03261D03*
X03395Y04222D03*
X04272Y03135D03*
X05634Y02236D03*
X02626Y0177D03*
X06304Y03121D03*
X03939D03*
X02139Y03738D03*
X04208Y03135D03*
X02604Y01734D03*
X06626Y03032D03*
X04152Y03135D03*
X02299Y01916D03*
X02724Y03521D03*
X01248Y02D03*
X02579Y0179D03*
X04068Y03135D03*
X02674Y03501D03*
X04234Y02725D03*
X06456Y03009D03*
X01691Y04079D03*
X03642Y00636D03*
X02259Y03261D03*
X03374Y03273D03*
X03368Y0305D03*
X04039Y03784D03*
X06476Y03231D03*
X04333Y03135D03*
X01557Y04229D03*
X06282Y03226D03*
X03806Y03235D03*
X01261Y02482D03*
X04114Y03135D03*
X06648Y03341D03*
X02888Y04221D03*
X0337Y02888D03*
X02258Y03741D03*
X01749Y0411D03*
X0257Y04283D03*
X01459Y03147D03*
X0144Y03557D03*
X01903Y04018D03*
X0229Y04217D03*
X0388Y03109D03*
X03623Y02587D03*
X03622Y03486D03*
X03491Y03297D03*
X03542Y03319D03*
X03344Y02996D03*
X03744Y03342D03*
X03653Y03293D03*
X03394Y03447D03*
X03436Y03457D03*
X03717Y03072D03*
X02799Y03616D03*
X03589Y01711D03*
X05733Y03556D03*
X05676Y03546D03*
X03603Y00682D03*
X02478Y00937D03*
X06548Y01531D03*
X06602Y01612D03*
Y01672D03*
Y01722D03*
X06601Y01777D03*
X06685Y01828D03*
X06699Y01881D03*
X06949Y02095D03*
X06607Y02176D03*
X06395Y02111D03*
X06048Y02171D03*
X06004Y02434D03*
X06274Y02391D03*
X06398Y02453D03*
X06397Y02501D03*
X06396Y02556D03*
X06397Y0261D03*
X06398Y02657D03*
X06372Y02909D03*
X0491Y04203D03*
X04387Y04206D03*
X03777Y04023D03*
X04085Y03892D03*
X04194Y03884D03*
X04431Y03135D03*
X0286Y03787D03*
X02724Y03729D03*
X03531Y0366D03*
X03269Y03788D03*
X01242Y01472D03*
X01256Y00942D03*
X00654Y0079D03*
X00655Y01028D03*
X00654Y01314D03*
X00653Y01551D03*
X00654Y01839D03*
Y02073D03*
Y02365D03*
X00653Y02593D03*
X02206Y01298D03*
X02205Y032D03*
X02502Y01316D03*
X02525Y02463D03*
X03342Y02263D03*
X03498Y02341D03*
X02429Y02621D03*
X01004Y00906D03*
X02446Y01437D03*
X01008Y0143D03*
X02409Y01967D03*
X01009Y01956D03*
X0102Y02481D03*
X02643Y01616D03*
X02666Y0164D03*
X01884Y03601D03*
X01754Y03661D03*
X03424Y03636D03*
X01549Y03621D03*
X03239Y03596D03*
X01574D03*
X03539Y03806D03*
X03219D03*
X02722Y03786D03*
X02139Y03611D03*
X02084Y03896D03*
X02083Y01411D03*
X02059Y01386D03*
Y03871D03*
X02029Y03836D03*
X01294Y04256D03*
X02004Y03816D03*
X02234Y03506D03*
X03529Y03481D03*
X05274Y03511D03*
X06284Y02501D03*
X02679Y03661D03*
X02774Y03566D03*
X02993Y03751D03*
X03699D03*
X03014Y03831D03*
X03699Y03836D03*
X04254Y03776D03*
X02894Y01561D03*
X02919Y01536D03*
X02274Y01506D03*
X02719Y01591D03*
X03724Y01675D03*
X06844Y01661D03*
X06424Y02181D03*
X06309Y03199D03*
X06339Y03151D03*
X04754Y04115D03*
X01779Y04156D03*
X03504Y04086D03*
X03854Y03151D03*
X03829Y03176D03*
X03799Y03201D03*
X06439Y03191D03*
X06354Y03331D03*
X06444Y03291D03*
X03302Y03344D03*
X06409Y03371D03*
X06447Y03396D03*
X06479Y03426D03*
X06509Y03456D03*
X03469D03*
X01849Y03701D03*
X06294D03*
G54D152*
X02531Y03853D03*
Y0283D03*
X00149D03*
Y03853D03*
M02*